(kicad_pcb
	(version 20260206)
	(generator "pcbnew")
	(generator_version "10.0")
	(general
		(thickness 1.6)
		(legacy_teardrops no)
	)
	(paper "A4")
	(title_block
		(title "04192023_DAF0TMB3IC0_F0TG_MB_C_brd_V02_OCP.brd")
		(comment 1 "Grand Teton / footprints 8319-8324 of 8354")
	)
	(layers
		(0 "F.Cu" signal "TOP")
		(4 "In1.Cu" signal "GND")
		(6 "In2.Cu" signal "IN1")
		(8 "In3.Cu" signal "GND1")
		(10 "In4.Cu" signal "IN2")
		(12 "In5.Cu" signal "GND2")
		(14 "In6.Cu" signal "IN3")
		(16 "In7.Cu" signal "GND3")
		(18 "In8.Cu" signal "VCC")
		(20 "In9.Cu" signal "VCC1")
		(22 "In10.Cu" signal "GND4")
		(24 "In11.Cu" signal "IN4")
		(26 "In12.Cu" signal "GND5")
		(28 "In13.Cu" signal "IN5")
		(30 "In14.Cu" signal "GND6")
		(32 "In15.Cu" signal "IN6")
		(34 "In16.Cu" signal "GND7")
		(2 "B.Cu" signal "BOTTOM")
		(9 "F.Adhes" user "F.Adhesive")
		(11 "B.Adhes" user "B.Adhesive")
		(13 "F.Paste" user "Package Geometry/Pastemask Top")
		(15 "B.Paste" user "Package Geometry/Pastemask Bottom")
		(5 "F.SilkS" user "Ref Des/Silkscreen Top")
		(7 "B.SilkS" user "Ref Des/Silkscreen Bottom")
		(1 "F.Mask" user "Board Geometry/Soldermask Top")
		(3 "B.Mask" user "Board Geometry/Soldermask Bottom")
		(17 "Dwgs.User" user "User.Drawings")
		(19 "Cmts.User" user "User.Comments")
		(21 "Eco1.User" user "User.Eco1")
		(23 "Eco2.User" user "User.Eco2")
		(25 "Edge.Cuts" user "Board Geometry/Outline")
		(27 "Margin" user)
		(31 "F.CrtYd" user "Package Geometry/Place Bound Top")
		(29 "B.CrtYd" user "Package Geometry/Place Bound Bottom")
		(35 "F.Fab" user "Ref Des/Assembly Top")
		(33 "B.Fab" user "Ref Des/Assembly Bottom")
	)
	(footprint ""
		(layer "B.Cu")
		(at 184.681114 -418.591238)
		(property "Reference" "R2805"
			(at 0 0 0)
			(layer "B.SilkS")
			(hide yes)
			(effects
				(font
					(size 1.27 1.27)
				)
				(justify mirror)
			)
		)
		(property "Value" ""
			(at 0 0 0)
			(layer "B.Fab")
			(effects
				(font
					(size 1.27 1.27)
				)
				(justify mirror)
			)
		)
		(duplicate_pad_numbers_are_jumpers no)
		(fp_line
			(start -0.7874 -0.4064)
			(end -0.7874 0.4064)
			(stroke
				(width 0.1524)
				(type default)
			)
			(layer "B.SilkS")
		)
		(fp_line
			(start -0.7874 0.4064)
			(end 0.7874 0.4064)
			(stroke
				(width 0.1524)
				(type default)
			)
			(layer "B.SilkS")
		)
		(fp_line
			(start 0.7874 -0.4064)
			(end -0.7874 -0.4064)
			(stroke
				(width 0.1524)
				(type default)
			)
			(layer "B.SilkS")
		)
		(fp_line
			(start 0.7874 0.4064)
			(end 0.7874 -0.4064)
			(stroke
				(width 0.1524)
				(type default)
			)
			(layer "B.SilkS")
		)
		(fp_line
			(start -0.67945 -0.3048)
			(end -0.67945 0.3048)
			(stroke
				(width 0.1)
				(type default)
			)
			(layer "B.Fab")
		)
		(fp_line
			(start -0.67945 0.3048)
			(end -0.120396 0.3048)
			(stroke
				(width 0.1)
				(type default)
			)
			(layer "B.Fab")
		)
		(fp_line
			(start -0.12065 -0.3048)
			(end -0.67945 -0.3048)
			(stroke
				(width 0.1)
				(type default)
			)
			(layer "B.Fab")
		)
		(fp_line
			(start -0.12065 -0.2794)
			(end -0.12065 -0.3048)
			(stroke
				(width 0.1)
				(type default)
			)
			(layer "B.Fab")
		)
		(fp_line
			(start -0.120396 0.2794)
			(end 0.12065 0.2794)
			(stroke
				(width 0.1)
				(type default)
			)
			(layer "B.Fab")
		)
		(fp_line
			(start -0.120396 0.3048)
			(end -0.120396 0.2794)
			(stroke
				(width 0.1)
				(type default)
			)
			(layer "B.Fab")
		)
		(fp_line
			(start 0.12065 -0.305054)
			(end 0.12065 -0.2794)
			(stroke
				(width 0.1)
				(type default)
			)
			(layer "B.Fab")
		)
		(fp_line
			(start 0.12065 -0.2794)
			(end -0.12065 -0.2794)
			(stroke
				(width 0.1)
				(type default)
			)
			(layer "B.Fab")
		)
		(fp_line
			(start 0.12065 0.2794)
			(end 0.12065 0.3048)
			(stroke
				(width 0.1)
				(type default)
			)
			(layer "B.Fab")
		)
		(fp_line
			(start 0.12065 0.3048)
			(end 0.67945 0.3048)
			(stroke
				(width 0.1)
				(type default)
			)
			(layer "B.Fab")
		)
		(fp_line
			(start 0.67945 -0.305054)
			(end 0.12065 -0.305054)
			(stroke
				(width 0.1)
				(type default)
			)
			(layer "B.Fab")
		)
		(fp_line
			(start 0.67945 0.3048)
			(end 0.67945 -0.305054)
			(stroke
				(width 0.1)
				(type default)
			)
			(layer "B.Fab")
		)
		(pad "1" smd circle
			(at 0.40005 0 180)
			(size 0 0)
			(layers "B.Cu" "B.Mask" "B.Paste")
			(net "P3V3_AUX")
		)
		(pad "2" smd circle
			(at -0.40005 0 180)
			(size 0 0)
			(layers "B.Cu" "B.Mask" "B.Paste")
			(net "SMB_FAN_3V3AUX_BUF_SCL")
		)
	)
	(footprint ""
		(layer "B.Cu")
		(at 92.281502 -207.38465 90)
		(property "Reference" "R486"
			(at 0 0 90)
			(layer "B.SilkS")
			(hide yes)
			(effects
				(font
					(size 1.27 1.27)
				)
				(justify mirror)
			)
		)
		(property "Value" ""
			(at 0 0 90)
			(layer "B.Fab")
			(effects
				(font
					(size 1.27 1.27)
				)
				(justify mirror)
			)
		)
		(duplicate_pad_numbers_are_jumpers no)
		(fp_line
			(start 0.7874 -0.4064)
			(end -0.7874 -0.4064)
			(stroke
				(width 0.1524)
				(type default)
			)
			(layer "B.SilkS")
		)
		(fp_line
			(start -0.7874 -0.4064)
			(end -0.7874 0.4064)
			(stroke
				(width 0.1524)
				(type default)
			)
			(layer "B.SilkS")
		)
		(fp_line
			(start 0.7874 0.4064)
			(end 0.7874 -0.4064)
			(stroke
				(width 0.1524)
				(type default)
			)
			(layer "B.SilkS")
		)
		(fp_line
			(start -0.7874 0.4064)
			(end 0.7874 0.4064)
			(stroke
				(width 0.1524)
				(type default)
			)
			(layer "B.SilkS")
		)
		(fp_line
			(start 0.67945 -0.305054)
			(end 0.12065 -0.305054)
			(stroke
				(width 0.1)
				(type default)
			)
			(layer "B.Fab")
		)
		(fp_line
			(start 0.12065 -0.305054)
			(end 0.12065 -0.2794)
			(stroke
				(width 0.1)
				(type default)
			)
			(layer "B.Fab")
		)
		(fp_line
			(start -0.12065 -0.3048)
			(end -0.67945 -0.3048)
			(stroke
				(width 0.1)
				(type default)
			)
			(layer "B.Fab")
		)
		(fp_line
			(start -0.67945 -0.3048)
			(end -0.67945 0.3048)
			(stroke
				(width 0.1)
				(type default)
			)
			(layer "B.Fab")
		)
		(fp_line
			(start 0.12065 -0.2794)
			(end -0.12065 -0.2794)
			(stroke
				(width 0.1)
				(type default)
			)
			(layer "B.Fab")
		)
		(fp_line
			(start -0.12065 -0.2794)
			(end -0.12065 -0.3048)
			(stroke
				(width 0.1)
				(type default)
			)
			(layer "B.Fab")
		)
		(fp_line
			(start 0.12065 0.2794)
			(end 0.12065 0.3048)
			(stroke
				(width 0.1)
				(type default)
			)
			(layer "B.Fab")
		)
		(fp_line
			(start -0.120396 0.2794)
			(end 0.12065 0.2794)
			(stroke
				(width 0.1)
				(type default)
			)
			(layer "B.Fab")
		)
		(fp_line
			(start 0.67945 0.3048)
			(end 0.67945 -0.305054)
			(stroke
				(width 0.1)
				(type default)
			)
			(layer "B.Fab")
		)
		(fp_line
			(start 0.12065 0.3048)
			(end 0.67945 0.3048)
			(stroke
				(width 0.1)
				(type default)
			)
			(layer "B.Fab")
		)
		(fp_line
			(start -0.120396 0.3048)
			(end -0.120396 0.2794)
			(stroke
				(width 0.1)
				(type default)
			)
			(layer "B.Fab")
		)
		(fp_line
			(start -0.67945 0.3048)
			(end -0.120396 0.3048)
			(stroke
				(width 0.1)
				(type default)
			)
			(layer "B.Fab")
		)
		(pad "1" smd circle
			(at 0.40005 0 270)
			(size 0 0)
			(layers "B.Cu" "B.Mask" "B.Paste")
			(net "CPU1_XTRIG_R2_L4")
		)
		(pad "2" smd circle
			(at -0.40005 0 270)
			(size 0 0)
			(layers "B.Cu" "B.Mask" "B.Paste")
			(net "CPU1_XTRIG_L4")
		)
	)
	(footprint ""
		(layer "B.Cu")
		(at 339.134958 -307.717952 180)
		(property "Reference" "R747"
			(at 0 0 0)
			(layer "B.SilkS")
			(hide yes)
			(effects
				(font
					(size 1.27 1.27)
				)
				(justify mirror)
			)
		)
		(property "Value" ""
			(at 0 0 0)
			(layer "B.Fab")
			(effects
				(font
					(size 1.27 1.27)
				)
				(justify mirror)
			)
		)
		(duplicate_pad_numbers_are_jumpers no)
		(fp_line
			(start 0.7874 0.4064)
			(end 0.7874 -0.4064)
			(stroke
				(width 0.1524)
				(type default)
			)
			(layer "B.SilkS")
		)
		(fp_line
			(start 0.7874 -0.4064)
			(end -0.7874 -0.4064)
			(stroke
				(width 0.1524)
				(type default)
			)
			(layer "B.SilkS")
		)
		(fp_line
			(start -0.7874 0.4064)
			(end 0.7874 0.4064)
			(stroke
				(width 0.1524)
				(type default)
			)
			(layer "B.SilkS")
		)
		(fp_line
			(start -0.7874 -0.4064)
			(end -0.7874 0.4064)
			(stroke
				(width 0.1524)
				(type default)
			)
			(layer "B.SilkS")
		)
		(fp_line
			(start 0.67945 0.3048)
			(end 0.67945 -0.305054)
			(stroke
				(width 0.1)
				(type default)
			)
			(layer "B.Fab")
		)
		(fp_line
			(start 0.67945 -0.305054)
			(end 0.12065 -0.305054)
			(stroke
				(width 0.1)
				(type default)
			)
			(layer "B.Fab")
		)
		(fp_line
			(start 0.12065 0.3048)
			(end 0.67945 0.3048)
			(stroke
				(width 0.1)
				(type default)
			)
			(layer "B.Fab")
		)
		(fp_line
			(start 0.12065 0.2794)
			(end 0.12065 0.3048)
			(stroke
				(width 0.1)
				(type default)
			)
			(layer "B.Fab")
		)
		(fp_line
			(start 0.12065 -0.2794)
			(end -0.12065 -0.2794)
			(stroke
				(width 0.1)
				(type default)
			)
			(layer "B.Fab")
		)
		(fp_line
			(start 0.12065 -0.305054)
			(end 0.12065 -0.2794)
			(stroke
				(width 0.1)
				(type default)
			)
			(layer "B.Fab")
		)
		(fp_line
			(start -0.120396 0.3048)
			(end -0.120396 0.2794)
			(stroke
				(width 0.1)
				(type default)
			)
			(layer "B.Fab")
		)
		(fp_line
			(start -0.120396 0.2794)
			(end 0.12065 0.2794)
			(stroke
				(width 0.1)
				(type default)
			)
			(layer "B.Fab")
		)
		(fp_line
			(start -0.12065 -0.2794)
			(end -0.12065 -0.3048)
			(stroke
				(width 0.1)
				(type default)
			)
			(layer "B.Fab")
		)
		(fp_line
			(start -0.12065 -0.3048)
			(end -0.67945 -0.3048)
			(stroke
				(width 0.1)
				(type default)
			)
			(layer "B.Fab")
		)
		(fp_line
			(start -0.67945 0.3048)
			(end -0.120396 0.3048)
			(stroke
				(width 0.1)
				(type default)
			)
			(layer "B.Fab")
		)
		(fp_line
			(start -0.67945 -0.3048)
			(end -0.67945 0.3048)
			(stroke
				(width 0.1)
				(type default)
			)
			(layer "B.Fab")
		)
		(pad "1" smd circle
			(at 0.40005 0)
			(size 0 0)
			(layers "B.Cu" "B.Mask" "B.Paste")
			(net "GND")
		)
		(pad "2" smd circle
			(at -0.40005 0)
			(size 0 0)
			(layers "B.Cu" "B.Mask" "B.Paste")
			(net "UART_CPU0_SCM_UART1_TX")
		)
	)
	(footprint ""
		(layer "B.Cu")
		(at 363.645958 -257.744976 180)
		(property "Reference" "C2565"
			(at 0 0 0)
			(layer "B.SilkS")
			(hide yes)
			(effects
				(font
					(size 1.27 1.27)
				)
				(justify mirror)
			)
		)
		(property "Value" ""
			(at 0 0 0)
			(layer "B.Fab")
			(effects
				(font
					(size 1.27 1.27)
				)
				(justify mirror)
			)
		)
		(duplicate_pad_numbers_are_jumpers no)
		(fp_line
			(start 0.7874 0.4064)
			(end 0.7874 -0.4064)
			(stroke
				(width 0.1524)
				(type default)
			)
			(layer "B.SilkS")
		)
		(fp_line
			(start 0.7874 -0.4064)
			(end -0.7874 -0.4064)
			(stroke
				(width 0.1524)
				(type default)
			)
			(layer "B.SilkS")
		)
		(fp_line
			(start -0.7874 0.4064)
			(end 0.7874 0.4064)
			(stroke
				(width 0.1524)
				(type default)
			)
			(layer "B.SilkS")
		)
		(fp_line
			(start -0.7874 -0.4064)
			(end -0.7874 0.4064)
			(stroke
				(width 0.1524)
				(type default)
			)
			(layer "B.SilkS")
		)
		(fp_line
			(start 0.67945 0.3048)
			(end 0.67945 -0.305054)
			(stroke
				(width 0.1)
				(type default)
			)
			(layer "B.Fab")
		)
		(fp_line
			(start 0.67945 -0.305054)
			(end 0.12065 -0.305054)
			(stroke
				(width 0.1)
				(type default)
			)
			(layer "B.Fab")
		)
		(fp_line
			(start 0.12065 0.3048)
			(end 0.67945 0.3048)
			(stroke
				(width 0.1)
				(type default)
			)
			(layer "B.Fab")
		)
		(fp_line
			(start 0.12065 0.2794)
			(end 0.12065 0.3048)
			(stroke
				(width 0.1)
				(type default)
			)
			(layer "B.Fab")
		)
		(fp_line
			(start 0.12065 -0.2794)
			(end -0.12065 -0.2794)
			(stroke
				(width 0.1)
				(type default)
			)
			(layer "B.Fab")
		)
		(fp_line
			(start 0.12065 -0.305054)
			(end 0.12065 -0.2794)
			(stroke
				(width 0.1)
				(type default)
			)
			(layer "B.Fab")
		)
		(fp_line
			(start -0.120396 0.3048)
			(end -0.120396 0.2794)
			(stroke
				(width 0.1)
				(type default)
			)
			(layer "B.Fab")
		)
		(fp_line
			(start -0.120396 0.2794)
			(end 0.12065 0.2794)
			(stroke
				(width 0.1)
				(type default)
			)
			(layer "B.Fab")
		)
		(fp_line
			(start -0.12065 -0.2794)
			(end -0.12065 -0.3048)
			(stroke
				(width 0.1)
				(type default)
			)
			(layer "B.Fab")
		)
		(fp_line
			(start -0.12065 -0.3048)
			(end -0.67945 -0.3048)
			(stroke
				(width 0.1)
				(type default)
			)
			(layer "B.Fab")
		)
		(fp_line
			(start -0.67945 0.3048)
			(end -0.120396 0.3048)
			(stroke
				(width 0.1)
				(type default)
			)
			(layer "B.Fab")
		)
		(fp_line
			(start -0.67945 -0.3048)
			(end -0.67945 0.3048)
			(stroke
				(width 0.1)
				(type default)
			)
			(layer "B.Fab")
		)
		(pad "1" smd circle
			(at 0.40005 0)
			(size 0 0)
			(layers "B.Cu" "B.Mask" "B.Paste")
			(net "PVDDCR_SOC_P0")
		)
		(pad "2" smd circle
			(at -0.40005 0)
			(size 0 0)
			(layers "B.Cu" "B.Mask" "B.Paste")
			(net "GND")
		)
	)
	(footprint ""
		(layer "B.Cu")
		(at 330.523342 -393.04468 180)
		(property "Reference" "R1032"
			(at 0 0 0)
			(layer "B.SilkS")
			(hide yes)
			(effects
				(font
					(size 1.27 1.27)
				)
				(justify mirror)
			)
		)
		(property "Value" ""
			(at 0 0 0)
			(layer "B.Fab")
			(effects
				(font
					(size 1.27 1.27)
				)
				(justify mirror)
			)
		)
		(duplicate_pad_numbers_are_jumpers no)
		(fp_line
			(start 0.32512 0.175006)
			(end 0.32512 -0.175006)
			(stroke
				(width 0.1)
				(type default)
			)
			(layer "B.Fab")
		)
		(fp_line
			(start 0.32512 -0.175006)
			(end -0.32512 -0.175006)
			(stroke
				(width 0.1)
				(type default)
			)
			(layer "B.Fab")
		)
		(fp_line
			(start -0.32512 0.175006)
			(end 0.32512 0.175006)
			(stroke
				(width 0.1)
				(type default)
			)
			(layer "B.Fab")
		)
		(fp_line
			(start -0.32512 -0.175006)
			(end -0.32512 0.175006)
			(stroke
				(width 0.1)
				(type default)
			)
			(layer "B.Fab")
		)
		(pad "1" smd rect
			(at 0.2667 0)
			(size 0.3048 0.381)
			(layers "B.Cu" "B.Mask" "B.Paste")
			(net "P1V8_CPU0_RT_1D")
		)
		(pad "2" smd rect
			(at -0.2667 0 180)
			(size 0.3048 0.381)
			(layers "B.Cu" "B.Mask" "B.Paste")
			(net "TEST1_RT_CPU0_P1")
		)
	)
	(footprint ""
		(layer "B.Cu")
		(at 456.028552 -380.027434 90)
		(property "Reference" "PC6569"
			(at -6.293104 2.441448 0)
			(unlocked yes)
			(layer "B.SilkS")
			(effects
				(font
					(size 0.7874 0.5842)
					(thickness 0.1524)
				)
				(justify left mirror)
			)
		)
		(property "Value" ""
			(at 0 0 90)
			(layer "B.Fab")
			(effects
				(font
					(size 1.27 1.27)
				)
				(justify mirror)
			)
		)
		(duplicate_pad_numbers_are_jumpers no)
		(fp_line
			(start 4.84378 -2.150618)
			(end 4.53898 -2.150618)
			(stroke
				(width 0.1524)
				(type default)
			)
			(layer "B.SilkS")
		)
		(fp_line
			(start 4.84378 -2.150618)
			(end 4.842256 2.163064)
			(stroke
				(width 0.1524)
				(type default)
			)
			(layer "B.SilkS")
		)
		(fp_line
			(start 4.69138 -2.150618)
			(end 4.692396 2.161032)
			(stroke
				(width 0.1524)
				(type default)
			)
			(layer "B.SilkS")
		)
		(fp_line
			(start 4.53898 -2.150618)
			(end 4.539742 2.152142)
			(stroke
				(width 0.1524)
				(type default)
			)
			(layer "B.SilkS")
		)
		(fp_line
			(start 4.53898 -2.15011)
			(end -4.53898 -2.15011)
			(stroke
				(width 0.1524)
				(type default)
			)
			(layer "B.SilkS")
		)
		(fp_line
			(start -4.53898 -2.15011)
			(end -4.53898 2.15011)
			(stroke
				(width 0.1524)
				(type default)
			)
			(layer "B.SilkS")
		)
		(fp_line
			(start 4.53898 2.15011)
			(end 4.53898 -2.15011)
			(stroke
				(width 0.1524)
				(type default)
			)
			(layer "B.SilkS")
		)
		(fp_line
			(start -4.53898 2.15011)
			(end 4.53898 2.15011)
			(stroke
				(width 0.1524)
				(type default)
			)
			(layer "B.SilkS")
		)
		(fp_line
			(start 4.83108 2.150364)
			(end 4.447794 2.149348)
			(stroke
				(width 0.1524)
				(type default)
			)
			(layer "B.SilkS")
		)
		(fp_line
			(start 3.64998 -2.15011)
			(end -3.64998 -2.15011)
			(stroke
				(width 0.1)
				(type default)
			)
			(layer "B.Fab")
		)
		(fp_line
			(start -3.64998 -2.15011)
			(end -3.64998 2.15011)
			(stroke
				(width 0.1)
				(type default)
			)
			(layer "B.Fab")
		)
		(fp_line
			(start 3.64998 2.15011)
			(end 3.64998 -2.15011)
			(stroke
				(width 0.1)
				(type default)
			)
			(layer "B.Fab")
		)
		(fp_line
			(start -3.64998 2.15011)
			(end 3.64998 2.15011)
			(stroke
				(width 0.1)
				(type default)
			)
			(layer "B.Fab")
		)
		(fp_text user "+"
			(at 5.235702 -3.104388 90)
			(unlocked yes)
			(layer "B.SilkS")
			(effects
				(font
					(size 1.905 1.4224)
					(thickness 0.1524)
				)
				(justify left mirror)
			)
		)
		(fp_text user "-"
			(at -4.313174 -0.094488 90)
			(unlocked yes)
			(layer "B.SilkS")
			(effects
				(font
					(size 1.905 1.4224)
					(thickness 0.1524)
				)
				(justify left mirror)
			)
		)
		(fp_text user "+"
			(at 6.214872 -0.337058 90)
			(unlocked yes)
			(layer "B.Fab")
			(effects
				(font
					(size 1.905 1.4224)
					(thickness 0.1524)
				)
				(justify left mirror)
			)
		)
		(fp_text user "-"
			(at -4.313174 -0.094488 90)
			(unlocked yes)
			(layer "B.Fab")
			(effects
				(font
					(size 1.905 1.4224)
					(thickness 0.1524)
				)
				(justify left mirror)
			)
		)
		(pad "1" smd rect
			(at 3.199892 0 270)
			(size 2.413 2.8194)
			(layers "B.Cu" "B.Mask" "B.Paste")
			(net "P0V9_CPU0_RT_2D")
		)
		(pad "2" smd rect
			(at -3.199892 0 270)
			(size 2.413 2.8194)
			(layers "B.Cu" "B.Mask" "B.Paste")
			(net "GND")
		)
	)
)
